FILE_TYPE = CONNECTIVITY;
{Allegro Design Entry HDL 17.2-2016 S081 (4005846) 1/11/2022}
"PAGE_NUMBER" = 147;
0"NC";
1"P3V3_AUX\g";
2"P3V3_AUX\g";
3"P3V3_AUX\g";
4"P3V3_AUX\g";
5"P3V3_AUX\g";
6"P3V3_AUX\g";
7"P3V3_AUX\g";
8"P3V3_AUX\g";
9"P3V3_AUX\g";
10"P3V3_AUX\g";
11"P3V3_AUX\g";
12"P3V3_AUX\g";
13"GND\g";
14"GND\g";
15"GND\g";
16"GND\g";
17"GND\g";
18"GND\g";
19"GND\g";
20"GND\g";
21"GND\g";
22"GND\g";
23"GND\g";
24"GND\g";
25"GND\g";
26"GND\g";
27"GND\g";
28"GND\g";
29"GND\g";
30"PRSNT_CABLE_GPU_A3_N";
31"PRSNT_CABLE_GPU_A3_ISO_N";
32"PRSNT_CABLE_GPU_A3";
33"PRSNT_CABLE_SWB_B1_ISO_N";
34"PRSNT_CABLE_SWB_B1";
35"PRSNT_CABLE_SWB_B1_N";
36"HGX_DETECT_N_ISO";
37"GPU_BASE_ID0";
38"GPU_BASE_ID1";
39"GPU_PEX_STRAP0";
40"GPU_PEX_STRAP1";
41"PRSNT_SWB_ISO_N";
42"PRSNT_SWB";
43"PRSNT_SWB_N";
44"PRSNT_CABLE_SWB_B2_ISO_N";
45"PRSNT_CABLE_SWB_B2_N";
46"PRSNT_CABLE_SWB_B2";
%"Q_RES"
"1","(550,4275)","0","pure_quanta","I11";
;
PART_NUMBER"CS11002FB07"
TOLERANCE"1%"
VALUE"100"
MATERIAL"EMPTY"
WATTAGE"1/16W"
PACK_TYPE"0402LF"
$LOCATION"R2656"
CDS_LIB"pure_quanta"
CDS_LOCATION"R2656"
$SEC"1"
CDS_SEC"1";
"B"
$PN"2"22;
"A"
$PN"1"36;
%"UNIVERSAL_GND"
"1","(1575,3025)","0","logical_power","I13";
;
HDL_POWER"GND"
CDS_LIB"logical_power";
"A"22;
%"Q_CAP"
"1","(-3625,8200)","0","pure_quanta","I15";
;
PART_NUMBER"TMP_QCH21006JB10"
VOLTAGE"50V"
PACK_TYPE"0402"
VALUE"1000PF"
TOLERANCE"5%"
MATERIAL"EMPTY"
$LOCATION"C2372"
CDS_LIB"pure_quanta"
CDS_LOCATION"C2372"
$SEC"1"
CDS_SEC"1";
"B"
$PN"2"26;
"A"
$PN"1"41;
%"UNIVERSAL_GND"
"1","(-3625,8000)","0","logical_power","I16";
;
HDL_POWER"GND"
CDS_LIB"logical_power";
"A"26;
%"UNIVERSAL_POWER"
"1","(-4400,8900)","0","logical_power","I17";
;
HDL_POWER"P3V3_AUX"
CDS_LIB"logical_power";
"A"9;
%"Q_RES"
"2","(-4400,8675)","0","pure_quanta","I18";
;
PART_NUMBER"CS24702JB10"
TOLERANCE"5%"
MATERIAL"CHIP"
PACK_TYPE"0402LF"
WATTAGE"1/16W"
VALUE"4.7K"
$LOCATION"R4726"
CDS_LIB"pure_quanta"
CDS_LOCATION"R4726"
$SEC"1"
CDS_SEC"1";
"A"
$PN"1"9;
"B"
$PN"2"41;
%"UNIVERSAL_GND"
"1","(-4400,7875)","0","logical_power","I19";
;
HDL_POWER"GND"
CDS_LIB"logical_power";
"A"25;
%"MOSFET_NCH_DUAL"
"2","(-4450,8250)","0","pure_quanta","I20";
;
PART_NUMBER"BAM138K0003"
MATERIAL"IC"
VALUE"PJT138K"
PART_TYPE"SMLF"
LOCATION"Q151"
CDS_LIB"pure_quanta"
NEEDS_NO_SIZE"TRUE"
CDS_LMAN_SYM_OUTLINE"-150,150,150,-150"
$SEC"2"
CDS_SEC"2";
"S2"
$PN"4"25;
"G2"
$PN"5"42;
"D2"
$PN"3"41;
%"Q_CAP"
"1","(-3500,6675)","0","pure_quanta","I22";
;
PART_NUMBER"TMP_QCH21006JB10"
VOLTAGE"50V"
PACK_TYPE"0402"
TOLERANCE"5%"
MATERIAL"EMPTY"
VALUE"1000PF"
$LOCATION"C2373"
CDS_LIB"pure_quanta"
CDS_LOCATION"C2373"
$SEC"1"
CDS_SEC"1";
"B"
$PN"2"27;
"A"
$PN"1"44;
%"UNIVERSAL_GND"
"1","(-3500,6475)","0","logical_power","I23";
;
HDL_POWER"GND"
CDS_LIB"logical_power";
"A"27;
%"UNIVERSAL_POWER"
"1","(-4275,7375)","0","logical_power","I24";
;
HDL_POWER"P3V3_AUX"
CDS_LIB"logical_power";
"A"10;
%"Q_RES"
"2","(-4275,7150)","0","pure_quanta","I25";
;
PART_NUMBER"CS24702JB10"
TOLERANCE"5%"
MATERIAL"CHIP"
PACK_TYPE"0402LF"
WATTAGE"1/16W"
VALUE"4.7K"
$LOCATION"R4733"
CDS_LIB"pure_quanta"
CDS_LOCATION"R4733"
$SEC"1"
CDS_SEC"1";
"A"
$PN"1"10;
"B"
$PN"2"44;
%"MOSFET_NCH_DUAL"
"2","(-4325,6725)","0","pure_quanta","I26";
;
PART_NUMBER"BAM138K0003"
VALUE"PJT138K"
PART_TYPE"SMLF"
MATERIAL"IC"
LOCATION"Q152"
CDS_LIB"pure_quanta"
NEEDS_NO_SIZE"TRUE"
CDS_LMAN_SYM_OUTLINE"-150,150,150,-150"
$SEC"2"
CDS_SEC"2";
"S2"
$PN"4"28;
"G2"
$PN"5"46;
"D2"
$PN"3"44;
%"UNIVERSAL_GND"
"1","(-4275,6350)","0","logical_power","I27";
;
HDL_POWER"GND"
CDS_LIB"logical_power";
"A"28;
%"Q_RES"
"2","(-5550,8550)","0","pure_quanta","I28";
;
PART_NUMBER"CS24702JB10"
TOLERANCE"5%"
PACK_TYPE"0402LF"
WATTAGE"1/16W"
MATERIAL"CHIP"
VALUE"4.7K"
$LOCATION"R4725"
CDS_LIB"pure_quanta"
CDS_LOCATION"R4725"
$SEC"1"
CDS_SEC"1";
"A"
$PN"1"8;
"B"
$PN"2"42;
%"UNIVERSAL_POWER"
"1","(-5550,8775)","0","logical_power","I29";
;
HDL_POWER"P3V3_AUX"
CDS_LIB"logical_power";
"A"8;
%"UNIVERSAL_GND"
"1","(-5550,7575)","0","logical_power","I30";
;
CDS_LIB"logical_power"
HDL_POWER"GND";
"A"24;
%"MOSFET_NCH_DUAL"
"1","(-5600,7950)","0","pure_quanta","I31";
;
PART_NUMBER"BAM138K0003"
PART_TYPE"SMLF"
MATERIAL"IC"
VALUE"PJT138K"
$LOCATION"Q151"
CDS_LIB"pure_quanta"
NEEDS_NO_SIZE"TRUE"
CDS_LMAN_SYM_OUTLINE"-150,150,150,-150"
CDS_LOCATION"Q151"
$SEC"1"
CDS_SEC"1";
"D1"
$PN"6"42;
"G1"
$PN"2"43;
"S1"
$PN"1"24;
%"UNIVERSAL_POWER"
"1","(-6725,8425)","0","logical_power","I32";
;
HDL_POWER"P3V3_AUX"
CDS_LIB"logical_power";
"A"7;
%"Q_RES"
"2","(-6725,8175)","0","pure_quanta","I33";
;
PART_NUMBER"CS31002FB08"
MATERIAL"CHIP"
TOLERANCE"1%"
PACK_TYPE"0402LF"
VALUE"10K"
WATTAGE"1/16W"
$LOCATION"R4727"
CDS_LIB"pure_quanta"
CDS_LOCATION"R4727"
$SEC"1"
CDS_SEC"1";
"A"
$PN"1"7;
"B"
$PN"2"43;
%"Q_RES"
"2","(-6700,7700)","0","pure_quanta","I34";
;
PART_NUMBER"CS41002FB09"
MATERIAL"EMPTY"
PACK_TYPE"0402LF"
WATTAGE"1/16W"
TOLERANCE"1%"
VALUE"100K"
$LOCATION"R4724"
CDS_LIB"pure_quanta"
CDS_LOCATION"R4724"
$SEC"1"
CDS_SEC"1";
"A"
$PN"1"43;
"B"
$PN"2"23;
%"UNIVERSAL_POWER"
"1","(-5425,7250)","0","logical_power","I35";
;
HDL_POWER"P3V3_AUX"
CDS_LIB"logical_power";
"A"11;
%"Q_RES"
"2","(-5425,7025)","0","pure_quanta","I36";
;
PART_NUMBER"CS24702JB10"
VALUE"4.7K"
MATERIAL"CHIP"
TOLERANCE"5%"
WATTAGE"1/16W"
PACK_TYPE"0402LF"
$LOCATION"R4732"
CDS_LIB"pure_quanta"
CDS_LOCATION"R4732"
$SEC"1"
CDS_SEC"1";
"A"
$PN"1"11;
"B"
$PN"2"46;
%"UNIVERSAL_GND"
"1","(-5425,6050)","0","logical_power","I37";
;
CDS_LIB"logical_power"
HDL_POWER"GND";
"A"29;
%"MOSFET_NCH_DUAL"
"1","(-5475,6425)","0","pure_quanta","I38";
;
PART_NUMBER"BAM138K0003"
VALUE"PJT138K"
PART_TYPE"SMLF"
MATERIAL"IC"
$LOCATION"Q152"
CDS_LMAN_SYM_OUTLINE"-150,150,150,-150"
NEEDS_NO_SIZE"TRUE"
CDS_LIB"pure_quanta"
CDS_LOCATION"Q152"
$SEC"1"
CDS_SEC"1";
"D1"
$PN"6"46;
"G1"
$PN"2"45;
"S1"
$PN"1"29;
%"UNIVERSAL_GND"
"1","(-6700,7425)","0","logical_power","I39";
;
HDL_POWER"GND"
CDS_LIB"logical_power";
"A"23;
%"UNIVERSAL_POWER"
"1","(-6600,6900)","0","logical_power","I40";
;
HDL_POWER"P3V3_AUX"
CDS_LIB"logical_power";
"A"12;
%"Q_RES"
"2","(-6600,6650)","0","pure_quanta","I41";
;
PART_NUMBER"CS31002FB08"
TOLERANCE"1%"
VALUE"10K"
WATTAGE"1/16W"
MATERIAL"CHIP"
PACK_TYPE"0402LF"
$LOCATION"R4730"
CDS_LIB"pure_quanta"
CDS_LOCATION"R4730"
$SEC"1"
CDS_SEC"1";
"A"
$PN"1"12;
"B"
$PN"2"45;
%"Q_RES"
"2","(-6575,6175)","0","pure_quanta","I42";
;
PART_NUMBER"CS41002FB09"
WATTAGE"1/16W"
MATERIAL"EMPTY"
TOLERANCE"1%"
VALUE"100K"
PACK_TYPE"0402LF"
$LOCATION"R4731"
CDS_LIB"pure_quanta"
CDS_LOCATION"R4731"
$SEC"1"
CDS_SEC"1";
"A"
$PN"1"45;
"B"
$PN"2"18;
%"UNIVERSAL_GND"
"1","(-6575,5900)","0","logical_power","I43";
;
CDS_LIB"logical_power"
HDL_POWER"GND";
"A"18;
%"Q_CAP"
"1","(-3275,5025)","0","pure_quanta","I47";
;
PART_NUMBER"TMP_QCH21006JB10"
VOLTAGE"50V"
PACK_TYPE"0402"
TOLERANCE"5%"
VALUE"1000PF"
MATERIAL"EMPTY"
$LOCATION"C2374"
CDS_LIB"pure_quanta"
CDS_LOCATION"C2374"
$SEC"1"
CDS_SEC"1";
"B"
$PN"2"21;
"A"
$PN"1"33;
%"UNIVERSAL_GND"
"1","(-3275,4825)","0","logical_power","I48";
;
HDL_POWER"GND"
CDS_LIB"logical_power";
"A"21;
%"UNIVERSAL_POWER"
"1","(-4050,5725)","0","logical_power","I49";
;
HDL_POWER"P3V3_AUX"
CDS_LIB"logical_power";
"A"3;
%"Q_RES"
"1","(525,3450)","0","pure_quanta","I5";
;
PART_NUMBER"CS00002JB13"
WATTAGE"1/16W"
MATERIAL"CHIP"
PACK_TYPE"0402LF"
VALUE"0"
TOLERANCE"5%"
$LOCATION"R3443"
CDS_LIB"pure_quanta"
CDS_LOCATION"R3443"
$SEC"1"
CDS_SEC"1";
"B"
$PN"2"22;
"A"
$PN"1"40;
%"Q_RES"
"2","(-4050,5500)","0","pure_quanta","I50";
;
PART_NUMBER"CS24702JB10"
VALUE"4.7K"
TOLERANCE"5%"
MATERIAL"CHIP"
PACK_TYPE"0402LF"
WATTAGE"1/16W"
$LOCATION"R4740"
CDS_LIB"pure_quanta"
CDS_LOCATION"R4740"
$SEC"1"
CDS_SEC"1";
"A"
$PN"1"3;
"B"
$PN"2"33;
%"MOSFET_NCH_DUAL"
"2","(-4100,5075)","0","pure_quanta","I51";
;
PART_NUMBER"BAM138K0003"
MATERIAL"IC"
PART_TYPE"SMLF"
VALUE"PJT138K"
LOCATION"Q153"
CDS_LIB"pure_quanta"
NEEDS_NO_SIZE"TRUE"
CDS_LMAN_SYM_OUTLINE"-150,150,150,-150"
$SEC"2"
CDS_SEC"2";
"S2"
$PN"4"20;
"G2"
$PN"5"34;
"D2"
$PN"3"33;
%"UNIVERSAL_GND"
"1","(-4050,4700)","0","logical_power","I52";
;
HDL_POWER"GND"
CDS_LIB"logical_power";
"A"20;
%"UNIVERSAL_POWER"
"1","(-5200,5600)","0","logical_power","I53";
;
HDL_POWER"P3V3_AUX"
CDS_LIB"logical_power";
"A"2;
%"Q_RES"
"2","(-5200,5375)","0","pure_quanta","I54";
;
PART_NUMBER"CS24702JB10"
WATTAGE"1/16W"
VALUE"4.7K"
MATERIAL"CHIP"
TOLERANCE"5%"
PACK_TYPE"0402LF"
$LOCATION"R4739"
CDS_LIB"pure_quanta"
CDS_LOCATION"R4739"
$SEC"1"
CDS_SEC"1";
"A"
$PN"1"2;
"B"
$PN"2"34;
%"MOSFET_NCH_DUAL"
"1","(-5250,4775)","0","pure_quanta","I55";
;
PART_NUMBER"BAM138K0003"
MATERIAL"IC"
PART_TYPE"SMLF"
VALUE"PJT138K"
LOCATION"Q153"
CDS_LMAN_SYM_OUTLINE"-150,150,150,-150"
NEEDS_NO_SIZE"TRUE"
CDS_LIB"pure_quanta"
$SEC"1"
CDS_SEC"1";
"D1"
$PN"6"34;
"G1"
$PN"2"35;
"S1"
$PN"1"19;
%"UNIVERSAL_GND"
"1","(-5200,4400)","0","logical_power","I56";
;
CDS_LIB"logical_power"
HDL_POWER"GND";
"A"19;
%"UNIVERSAL_POWER"
"1","(-6375,5250)","0","logical_power","I57";
;
HDL_POWER"P3V3_AUX"
CDS_LIB"logical_power";
"A"1;
%"Q_RES"
"2","(-6375,5000)","0","pure_quanta","I58";
;
PART_NUMBER"CS31002FB08"
TOLERANCE"1%"
WATTAGE"1/16W"
VALUE"10K"
MATERIAL"CHIP"
PACK_TYPE"0402LF"
$LOCATION"R4737"
CDS_LIB"pure_quanta"
CDS_LOCATION"R4737"
$SEC"1"
CDS_SEC"1";
"A"
$PN"1"1;
"B"
$PN"2"35;
%"Q_RES"
"1","(525,3650)","0","pure_quanta","I6";
;
PART_NUMBER"CS00002JB13"
PACK_TYPE"0402LF"
VALUE"0"
MATERIAL"CHIP"
TOLERANCE"5%"
WATTAGE"1/16W"
$LOCATION"R3442"
CDS_LIB"pure_quanta"
CDS_LOCATION"R3442"
$SEC"1"
CDS_SEC"1";
"B"
$PN"2"22;
"A"
$PN"1"39;
%"Q_RES"
"2","(-6350,4525)","0","pure_quanta","I60";
;
PART_NUMBER"CS41002FB09"
MATERIAL"EMPTY"
PACK_TYPE"0402LF"
WATTAGE"1/16W"
TOLERANCE"1%"
VALUE"100K"
$LOCATION"R4738"
CDS_LIB"pure_quanta"
CDS_LOCATION"R4738"
$SEC"1"
CDS_SEC"1";
"A"
$PN"1"35;
"B"
$PN"2"17;
%"UNIVERSAL_GND"
"1","(-6350,4250)","0","logical_power","I61";
;
HDL_POWER"GND"
CDS_LIB"logical_power";
"A"17;
%"MOSFET_NCH_DUAL"
"2","(-4075,3675)","0","pure_quanta","I62";
;
PART_NUMBER"BAM138K0003"
MATERIAL"IC"
VALUE"PJT138K"
PART_TYPE"SMLF"
LOCATION"Q154"
CDS_LMAN_SYM_OUTLINE"-150,150,150,-150"
NEEDS_NO_SIZE"TRUE"
CDS_LIB"pure_quanta"
$SEC"2"
CDS_SEC"2";
"S2"
$PN"4"14;
"G2"
$PN"5"32;
"D2"
$PN"3"31;
%"UNIVERSAL_POWER"
"1","(-4025,4325)","0","logical_power","I64";
;
HDL_POWER"P3V3_AUX"
CDS_LIB"logical_power";
"A"5;
%"Q_RES"
"2","(-4025,4100)","0","pure_quanta","I65";
;
PART_NUMBER"CS24702JB10"
WATTAGE"1/16W"
TOLERANCE"5%"
VALUE"4.7K"
MATERIAL"CHIP"
PACK_TYPE"0402LF"
$LOCATION"R4801"
CDS_LIB"pure_quanta"
CDS_LOCATION"R4801"
$SEC"1"
CDS_SEC"1";
"A"
$PN"1"5;
"B"
$PN"2"31;
%"Q_CAP"
"1","(-3250,3625)","0","pure_quanta","I66";
;
PART_NUMBER"TMP_QCH21006JB10"
MATERIAL"EMPTY"
VALUE"1000PF"
TOLERANCE"5%"
PACK_TYPE"0402"
VOLTAGE"50V"
$LOCATION"C2391"
CDS_LIB"pure_quanta"
CDS_LOCATION"C2391"
$SEC"1"
CDS_SEC"1";
"B"
$PN"2"13;
"A"
$PN"1"31;
%"UNIVERSAL_GND"
"1","(-3250,3425)","0","logical_power","I67";
;
CDS_LIB"logical_power"
HDL_POWER"GND";
"A"13;
%"UNIVERSAL_GND"
"1","(-4025,3300)","0","logical_power","I68";
;
CDS_LIB"logical_power"
HDL_POWER"GND";
"A"14;
%"UNIVERSAL_POWER"
"1","(-5175,4200)","0","logical_power","I69";
;
HDL_POWER"P3V3_AUX"
CDS_LIB"logical_power";
"A"6;
%"Q_RES"
"1","(525,3850)","0","pure_quanta","I7";
;
PART_NUMBER"CS00002JB13"
TOLERANCE"5%"
WATTAGE"1/16W"
MATERIAL"CHIP"
VALUE"0"
PACK_TYPE"0402LF"
$LOCATION"R3441"
CDS_LIB"pure_quanta"
CDS_LOCATION"R3441"
$SEC"1"
CDS_SEC"1";
"B"
$PN"2"22;
"A"
$PN"1"38;
%"Q_RES"
"2","(-5175,3975)","0","pure_quanta","I70";
;
PART_NUMBER"CS24702JB10"
VALUE"4.7K"
TOLERANCE"5%"
PACK_TYPE"0402LF"
MATERIAL"CHIP"
WATTAGE"1/16W"
$LOCATION"R4800"
CDS_LIB"pure_quanta"
CDS_LOCATION"R4800"
$SEC"1"
CDS_SEC"1";
"A"
$PN"1"6;
"B"
$PN"2"32;
%"MOSFET_NCH_DUAL"
"1","(-5225,3375)","0","pure_quanta","I71";
;
PART_NUMBER"BAM138K0003"
PART_TYPE"SMLF"
VALUE"PJT138K"
MATERIAL"IC"
LOCATION"Q154"
CDS_LIB"pure_quanta"
NEEDS_NO_SIZE"TRUE"
CDS_LMAN_SYM_OUTLINE"-150,150,150,-150"
$SEC"1"
CDS_SEC"1";
"D1"
$PN"6"32;
"G1"
$PN"2"30;
"S1"
$PN"1"15;
%"UNIVERSAL_GND"
"1","(-5175,3000)","0","logical_power","I72";
;
HDL_POWER"GND"
CDS_LIB"logical_power";
"A"15;
%"UNIVERSAL_POWER"
"1","(-6350,3850)","0","logical_power","I74";
;
HDL_POWER"P3V3_AUX"
CDS_LIB"logical_power";
"A"4;
%"Q_RES"
"2","(-6350,3600)","0","pure_quanta","I75";
;
PART_NUMBER"CS31002FB08"
PACK_TYPE"0402LF"
MATERIAL"CHIP"
VALUE"10K"
TOLERANCE"1%"
WATTAGE"1/16W"
$LOCATION"R4798"
CDS_LIB"pure_quanta"
CDS_LOCATION"R4798"
$SEC"1"
CDS_SEC"1";
"A"
$PN"1"4;
"B"
$PN"2"30;
%"Q_RES"
"2","(-6325,3125)","0","pure_quanta","I76";
;
PART_NUMBER"CS41002FB09"
TOLERANCE"1%"
WATTAGE"1/16W"
PACK_TYPE"0402LF"
MATERIAL"EMPTY"
VALUE"100K"
$LOCATION"R4799"
CDS_LIB"pure_quanta"
CDS_LOCATION"R4799"
$SEC"1"
CDS_SEC"1";
"A"
$PN"1"30;
"B"
$PN"2"16;
%"UNIVERSAL_GND"
"1","(-6325,2850)","0","logical_power","I77";
;
CDS_LIB"logical_power"
HDL_POWER"GND";
"A"16;
%"Q_RES"
"1","(525,4050)","0","pure_quanta","I8";
;
PART_NUMBER"CS00002JB13"
PACK_TYPE"0402LF"
TOLERANCE"5%"
MATERIAL"EMPTY"
WATTAGE"1/16W"
VALUE"0"
$LOCATION"R3440"
CDS_LIB"pure_quanta"
CDS_LOCATION"R3440"
$SEC"1"
CDS_SEC"1";
"B"
$PN"2"22;
"A"
$PN"1"37;
END.
